(kicad_pcb
	(version 20260206)
	(generator "pcbnew")
	(generator_version "10.0")
	(general
		(thickness 1.6)
		(legacy_teardrops no)
	)
	(paper "A4")
	(title_block
		(title "peb — Lightning_PEB_BRD.brd")
		(comment 1 "Lightning (Wiwynn / Facebook NVMe JBOF) / footprints 1943-1949 of 2563")
	)
	(layers
		(0 "F.Cu" signal "TOP")
		(4 "In1.Cu" signal "L2GND")
		(6 "In2.Cu" signal "L3")
		(8 "In3.Cu" signal "L4VCC")
		(10 "In4.Cu" signal "L5VCC")
		(12 "In5.Cu" signal "L6")
		(14 "In6.Cu" signal "L7GND")
		(2 "B.Cu" signal "BOTTOM")
		(9 "F.Adhes" user "F.Adhesive")
		(11 "B.Adhes" user "B.Adhesive")
		(13 "F.Paste" user "Package Geometry/Pastemask Top")
		(15 "B.Paste" user "Package Geometry/Pastemask Bottom")
		(5 "F.SilkS" user "Ref Des/Silkscreen Top")
		(7 "B.SilkS" user "Ref Des/Silkscreen Bottom")
		(1 "F.Mask" user "Board Geometry/Soldermask Top")
		(3 "B.Mask" user "Board Geometry/Soldermask Bottom")
		(17 "Dwgs.User" user "User.Drawings")
		(19 "Cmts.User" user "User.Comments")
		(21 "Eco1.User" user "User.Eco1")
		(23 "Eco2.User" user "User.Eco2")
		(25 "Edge.Cuts" user "Board Geometry/Outline")
		(27 "Margin" user)
		(31 "F.CrtYd" user "Package Geometry/Place Bound Top")
		(29 "B.CrtYd" user "Package Geometry/Place Bound Bottom")
		(35 "F.Fab" user "Ref Des/Assembly Top")
		(33 "B.Fab" user "Ref Des/Assembly Bottom")
	)
	(footprint ""
		(layer "B.Cu")
		(at 252.603 -45.000672 -90)
		(property "Reference" "C613"
			(at 0 0 90)
			(layer "B.SilkS")
			(hide yes)
			(effects
				(font
					(size 1.27 1.27)
				)
				(justify mirror)
			)
		)
		(property "Value" "SCD1U16V1KX-1-GP"
			(at 2.8321 -1.7399 270)
			(unlocked yes)
			(layer "B.Fab")
			(hide yes)
			(effects
				(font
					(size 1.016 1.016)
					(thickness 0.1524)
				)
				(justify mirror)
			)
		)
		(property "Device Type" "C0201H13"
			(at 2.8321 -3.2639 270)
			(unlocked yes)
			(layer "B.Fab")
			(hide yes)
			(effects
				(font
					(size 1.016 1.016)
					(thickness 0.1524)
				)
				(justify mirror)
			)
		)
		(duplicate_pad_numbers_are_jumpers no)
		(fp_rect
			(start 0.2794 0.6477)
			(end -0.2794 -0.6477)
			(stroke
				(width 0)
				(type default)
			)
			(fill no)
			(layer "B.CrtYd")
		)
		(fp_rect
			(start 0.2794 0.6477)
			(end -0.2794 -0.6477)
			(stroke
				(width 0)
				(type default)
			)
			(fill no)
			(layer "B.Fab")
		)
		(pad "1" smd custom
			(at 0 -0.2794 90)
			(size 0.0762 0.0762)
			(layers "B.Cu" "B.Mask" "B.Paste")
			(net "DUT_AVD_PCIE")
			(options
				(clearance outline)
				(anchor circle)
			)
			(primitives
				(gr_poly
					(pts
						(arc
							(start 0.1524 0.127)
							(mid 0.137521 0.162921)
							(end 0.1016 0.1778)
						)
						(arc
							(start -0.1016 0.1778)
							(mid -0.137521 0.162921)
							(end -0.1524 0.127)
						)
						(arc
							(start -0.1524 -0.127)
							(mid -0.137521 -0.162921)
							(end -0.1016 -0.1778)
						)
						(arc
							(start 0.1016 -0.1778)
							(mid 0.137521 -0.162921)
							(end 0.1524 -0.127)
						)
					)
					(width 0)
					(fill yes)
				)
			)
		)
		(pad "2" smd custom
			(at 0 0.2794 90)
			(size 0.0762 0.0762)
			(layers "B.Cu" "B.Mask" "B.Paste")
			(net "GND")
			(options
				(clearance outline)
				(anchor circle)
			)
			(primitives
				(gr_poly
					(pts
						(arc
							(start 0.1524 0.127)
							(mid 0.137521 0.162921)
							(end 0.1016 0.1778)
						)
						(arc
							(start -0.1016 0.1778)
							(mid -0.137521 0.162921)
							(end -0.1524 0.127)
						)
						(arc
							(start -0.1524 -0.127)
							(mid -0.137521 -0.162921)
							(end -0.1016 -0.1778)
						)
						(arc
							(start 0.1016 -0.1778)
							(mid 0.137521 -0.162921)
							(end 0.1524 -0.127)
						)
					)
					(width 0)
					(fill yes)
				)
			)
		)
	)
	(footprint ""
		(layer "B.Cu")
		(at 57.15 -136.271)
		(property "Reference" "R5763"
			(at 0 0 0)
			(layer "B.SilkS")
			(hide yes)
			(effects
				(font
					(size 1.27 1.27)
				)
				(justify mirror)
			)
		)
		(property "Value" "1KR2F-3-GP"
			(at -0.064008 -3.993896 0)
			(unlocked yes)
			(layer "B.Fab")
			(hide yes)
			(effects
				(font
					(size 1.016 1.016)
					(thickness 0.1524)
				)
				(justify mirror)
			)
		)
		(property "Device Type" "R402H16"
			(at -0.064008 -5.517896 0)
			(unlocked yes)
			(layer "B.Fab")
			(hide yes)
			(effects
				(font
					(size 1.016 1.016)
					(thickness 0.1524)
				)
				(justify mirror)
			)
		)
		(duplicate_pad_numbers_are_jumpers no)
		(fp_line
			(start -0.508 -0.9398)
			(end 0.508 -0.9398)
			(stroke
				(width 0.1524)
				(type default)
			)
			(layer "B.SilkS")
		)
		(fp_line
			(start 0.508 -0.9398)
			(end 0.508 0.9398)
			(stroke
				(width 0.1524)
				(type default)
			)
			(layer "B.SilkS")
		)
		(fp_rect
			(start 0.508 0.9398)
			(end -0.508 -0.9398)
			(stroke
				(width 0)
				(type default)
			)
			(fill no)
			(layer "B.CrtYd")
		)
		(fp_rect
			(start 0.508 0.9398)
			(end -0.508 -0.9398)
			(stroke
				(width 0)
				(type default)
			)
			(fill no)
			(layer "B.Fab")
		)
		(pad "1" smd custom
			(at 0 -0.4445 180)
			(size 0.1397 0.1397)
			(layers "B.Cu" "B.Mask" "B.Paste")
			(net "P0V9_E")
			(options
				(clearance outline)
				(anchor circle)
			)
			(primitives
				(gr_poly
					(pts
						(arc
							(start -0.1778 0.2794)
							(mid -0.249642 0.249642)
							(end -0.2794 0.1778)
						)
						(arc
							(start -0.2794 -0.1778)
							(mid -0.249642 -0.249642)
							(end -0.1778 -0.2794)
						)
						(arc
							(start 0.1778 -0.2794)
							(mid 0.249642 -0.249642)
							(end 0.2794 -0.1778)
						)
						(arc
							(start 0.2794 0.1778)
							(mid 0.249642 0.249642)
							(end 0.1778 0.2794)
						)
					)
					(width 0)
					(fill yes)
				)
			)
		)
		(pad "2" smd custom
			(at 0 0.4445 180)
			(size 0.1397 0.1397)
			(layers "B.Cu" "B.Mask" "B.Paste")
			(net "ADC_P0V9_E")
			(options
				(clearance outline)
				(anchor circle)
			)
			(primitives
				(gr_poly
					(pts
						(arc
							(start -0.1778 0.2794)
							(mid -0.249642 0.249642)
							(end -0.2794 0.1778)
						)
						(arc
							(start -0.2794 -0.1778)
							(mid -0.249642 -0.249642)
							(end -0.1778 -0.2794)
						)
						(arc
							(start 0.1778 -0.2794)
							(mid 0.249642 -0.249642)
							(end 0.2794 -0.1778)
						)
						(arc
							(start 0.2794 0.1778)
							(mid 0.249642 0.249642)
							(end 0.1778 0.2794)
						)
					)
					(width 0)
					(fill yes)
				)
			)
		)
	)
	(footprint ""
		(layer "B.Cu")
		(at 176.063402 -62.714632)
		(property "Reference" "PC205"
			(at 0 0 0)
			(layer "B.SilkS")
			(hide yes)
			(effects
				(font
					(size 1.27 1.27)
				)
				(justify mirror)
			)
		)
		(property "Value" "SC22U6D3V5MX-5-GP"
			(at 0.0762 -6.1214 0)
			(unlocked yes)
			(layer "B.Fab")
			(hide yes)
			(effects
				(font
					(size 1.016 1.016)
					(thickness 0.1524)
				)
				(justify mirror)
			)
		)
		(property "Device Type" "C805H56"
			(at 0.0762 -8.1534 0)
			(unlocked yes)
			(layer "B.Fab")
			(hide yes)
			(effects
				(font
					(size 1.016 1.016)
					(thickness 0.1524)
				)
				(justify mirror)
			)
		)
		(duplicate_pad_numbers_are_jumpers no)
		(fp_line
			(start -0.635 0)
			(end 0.635 0)
			(stroke
				(width 0.508)
				(type default)
			)
			(layer "B.SilkS")
		)
		(fp_rect
			(start 0.9652 1.778)
			(end -0.9652 -1.778)
			(stroke
				(width 0)
				(type default)
			)
			(fill no)
			(layer "B.CrtYd")
		)
		(fp_poly
			(pts
				(xy 0.9652 -1.778) (xy -0.9652 -1.778) (xy -0.9652 1.778) (xy 0.9652 1.778)
			)
			(stroke
				(width 0)
				(type default)
			)
			(fill no)
			(layer "B.Fab")
		)
		(pad "1" smd rect
			(at 0 -0.9652 180)
			(size 1.397 1.143)
			(layers "B.Cu" "B.Mask" "B.Paste")
			(net "P0V9")
		)
		(pad "2" smd rect
			(at 0 0.9652 180)
			(size 1.397 1.143)
			(layers "B.Cu" "B.Mask" "B.Paste")
			(net "GND")
		)
	)
	(footprint ""
		(layer "B.Cu")
		(at 144.86763 -33.53562)
		(property "Reference" "R2927"
			(at 0 0 0)
			(layer "B.SilkS")
			(hide yes)
			(effects
				(font
					(size 1.27 1.27)
				)
				(justify mirror)
			)
		)
		(property "Value" "0R2J-2-GP"
			(at -0.064008 -3.993896 0)
			(unlocked yes)
			(layer "B.Fab")
			(hide yes)
			(effects
				(font
					(size 1.016 1.016)
					(thickness 0.1524)
				)
				(justify mirror)
			)
		)
		(property "Device Type" "R402H16"
			(at -0.064008 -5.517896 0)
			(unlocked yes)
			(layer "B.Fab")
			(hide yes)
			(effects
				(font
					(size 1.016 1.016)
					(thickness 0.1524)
				)
				(justify mirror)
			)
		)
		(duplicate_pad_numbers_are_jumpers no)
		(fp_line
			(start -0.508 -0.9398)
			(end 0.508 -0.9398)
			(stroke
				(width 0.1524)
				(type default)
			)
			(layer "B.SilkS")
		)
		(fp_line
			(start 0.508 -0.9398)
			(end 0.508 0.9398)
			(stroke
				(width 0.1524)
				(type default)
			)
			(layer "B.SilkS")
		)
		(fp_rect
			(start 0.508 0.9398)
			(end -0.508 -0.9398)
			(stroke
				(width 0)
				(type default)
			)
			(fill no)
			(layer "B.CrtYd")
		)
		(fp_rect
			(start 0.508 0.9398)
			(end -0.508 -0.9398)
			(stroke
				(width 0)
				(type default)
			)
			(fill no)
			(layer "B.Fab")
		)
		(pad "1" smd custom
			(at 0 -0.4445 180)
			(size 0.1397 0.1397)
			(layers "B.Cu" "B.Mask" "B.Paste")
			(net "CBL_PRSNT_N_2")
			(options
				(clearance outline)
				(anchor circle)
			)
			(primitives
				(gr_poly
					(pts
						(arc
							(start -0.1778 0.2794)
							(mid -0.249642 0.249642)
							(end -0.2794 0.1778)
						)
						(arc
							(start -0.2794 -0.1778)
							(mid -0.249642 -0.249642)
							(end -0.1778 -0.2794)
						)
						(arc
							(start 0.1778 -0.2794)
							(mid 0.249642 -0.249642)
							(end 0.2794 -0.1778)
						)
						(arc
							(start 0.2794 0.1778)
							(mid 0.249642 0.249642)
							(end 0.1778 0.2794)
						)
					)
					(width 0)
					(fill yes)
				)
			)
		)
		(pad "2" smd custom
			(at 0 0.4445 180)
			(size 0.1397 0.1397)
			(layers "B.Cu" "B.Mask" "B.Paste")
			(net "8644_SDA_R_2")
			(options
				(clearance outline)
				(anchor circle)
			)
			(primitives
				(gr_poly
					(pts
						(arc
							(start -0.1778 0.2794)
							(mid -0.249642 0.249642)
							(end -0.2794 0.1778)
						)
						(arc
							(start -0.2794 -0.1778)
							(mid -0.249642 -0.249642)
							(end -0.1778 -0.2794)
						)
						(arc
							(start 0.1778 -0.2794)
							(mid 0.249642 -0.249642)
							(end 0.2794 -0.1778)
						)
						(arc
							(start 0.2794 0.1778)
							(mid 0.249642 0.249642)
							(end 0.1778 0.2794)
						)
					)
					(width 0)
					(fill yes)
				)
			)
		)
	)
	(footprint ""
		(layer "B.Cu")
		(at 63.49873 -25.516332)
		(property "Reference" "R700"
			(at 0 0 0)
			(layer "B.SilkS")
			(hide yes)
			(effects
				(font
					(size 1.27 1.27)
				)
				(justify mirror)
			)
		)
		(property "Value" "4K7R2F-GP"
			(at -0.064008 -3.993896 0)
			(unlocked yes)
			(layer "B.Fab")
			(hide yes)
			(effects
				(font
					(size 1.016 1.016)
					(thickness 0.1524)
				)
				(justify mirror)
			)
		)
		(property "Device Type" "R402H16"
			(at -0.064008 -5.517896 0)
			(unlocked yes)
			(layer "B.Fab")
			(hide yes)
			(effects
				(font
					(size 1.016 1.016)
					(thickness 0.1524)
				)
				(justify mirror)
			)
		)
		(duplicate_pad_numbers_are_jumpers no)
		(fp_line
			(start -0.508 -0.9398)
			(end 0.508 -0.9398)
			(stroke
				(width 0.1524)
				(type default)
			)
			(layer "B.SilkS")
		)
		(fp_line
			(start 0.508 -0.9398)
			(end 0.508 0.9398)
			(stroke
				(width 0.1524)
				(type default)
			)
			(layer "B.SilkS")
		)
		(fp_rect
			(start 0.508 0.9398)
			(end -0.508 -0.9398)
			(stroke
				(width 0)
				(type default)
			)
			(fill no)
			(layer "B.CrtYd")
		)
		(fp_rect
			(start 0.508 0.9398)
			(end -0.508 -0.9398)
			(stroke
				(width 0)
				(type default)
			)
			(fill no)
			(layer "B.Fab")
		)
		(pad "1" smd custom
			(at 0 -0.4445 180)
			(size 0.1397 0.1397)
			(layers "B.Cu" "B.Mask" "B.Paste")
			(net "P3V3_STBY")
			(options
				(clearance outline)
				(anchor circle)
			)
			(primitives
				(gr_poly
					(pts
						(arc
							(start -0.1778 0.2794)
							(mid -0.249642 0.249642)
							(end -0.2794 0.1778)
						)
						(arc
							(start -0.2794 -0.1778)
							(mid -0.249642 -0.249642)
							(end -0.1778 -0.2794)
						)
						(arc
							(start 0.1778 -0.2794)
							(mid 0.249642 -0.249642)
							(end 0.2794 -0.1778)
						)
						(arc
							(start 0.2794 0.1778)
							(mid 0.249642 0.249642)
							(end 0.1778 0.2794)
						)
					)
					(width 0)
					(fill yes)
				)
			)
		)
		(pad "2" smd custom
			(at 0 0.4445 180)
			(size 0.1397 0.1397)
			(layers "B.Cu" "B.Mask" "B.Paste")
			(net "IPMB_CLK")
			(options
				(clearance outline)
				(anchor circle)
			)
			(primitives
				(gr_poly
					(pts
						(arc
							(start -0.1778 0.2794)
							(mid -0.249642 0.249642)
							(end -0.2794 0.1778)
						)
						(arc
							(start -0.2794 -0.1778)
							(mid -0.249642 -0.249642)
							(end -0.1778 -0.2794)
						)
						(arc
							(start 0.1778 -0.2794)
							(mid 0.249642 -0.249642)
							(end 0.2794 -0.1778)
						)
						(arc
							(start 0.2794 0.1778)
							(mid 0.249642 0.249642)
							(end 0.1778 0.2794)
						)
					)
					(width 0)
					(fill yes)
				)
			)
		)
	)
	(footprint ""
		(layer "B.Cu")
		(at 166.37 -33.528)
		(property "Reference" "R2922"
			(at 0 0 0)
			(layer "B.SilkS")
			(hide yes)
			(effects
				(font
					(size 1.27 1.27)
				)
				(justify mirror)
			)
		)
		(property "Value" "0R2J-2-GP"
			(at -0.064008 -3.993896 0)
			(unlocked yes)
			(layer "B.Fab")
			(hide yes)
			(effects
				(font
					(size 1.016 1.016)
					(thickness 0.1524)
				)
				(justify mirror)
			)
		)
		(property "Device Type" "R402H16"
			(at -0.064008 -5.517896 0)
			(unlocked yes)
			(layer "B.Fab")
			(hide yes)
			(effects
				(font
					(size 1.016 1.016)
					(thickness 0.1524)
				)
				(justify mirror)
			)
		)
		(duplicate_pad_numbers_are_jumpers no)
		(fp_line
			(start -0.508 -0.9398)
			(end 0.508 -0.9398)
			(stroke
				(width 0.1524)
				(type default)
			)
			(layer "B.SilkS")
		)
		(fp_line
			(start 0.508 -0.9398)
			(end 0.508 0.9398)
			(stroke
				(width 0.1524)
				(type default)
			)
			(layer "B.SilkS")
		)
		(fp_rect
			(start 0.508 0.9398)
			(end -0.508 -0.9398)
			(stroke
				(width 0)
				(type default)
			)
			(fill no)
			(layer "B.CrtYd")
		)
		(fp_rect
			(start 0.508 0.9398)
			(end -0.508 -0.9398)
			(stroke
				(width 0)
				(type default)
			)
			(fill no)
			(layer "B.Fab")
		)
		(pad "1" smd custom
			(at 0 -0.4445 180)
			(size 0.1397 0.1397)
			(layers "B.Cu" "B.Mask" "B.Paste")
			(net "CBL_PRSNT_N_4")
			(options
				(clearance outline)
				(anchor circle)
			)
			(primitives
				(gr_poly
					(pts
						(arc
							(start -0.1778 0.2794)
							(mid -0.249642 0.249642)
							(end -0.2794 0.1778)
						)
						(arc
							(start -0.2794 -0.1778)
							(mid -0.249642 -0.249642)
							(end -0.1778 -0.2794)
						)
						(arc
							(start 0.1778 -0.2794)
							(mid 0.249642 -0.249642)
							(end 0.2794 -0.1778)
						)
						(arc
							(start 0.2794 0.1778)
							(mid 0.249642 0.249642)
							(end 0.1778 0.2794)
						)
					)
					(width 0)
					(fill yes)
				)
			)
		)
		(pad "2" smd custom
			(at 0 0.4445 180)
			(size 0.1397 0.1397)
			(layers "B.Cu" "B.Mask" "B.Paste")
			(net "8644_CBL_PRSNT_R_4")
			(options
				(clearance outline)
				(anchor circle)
			)
			(primitives
				(gr_poly
					(pts
						(arc
							(start -0.1778 0.2794)
							(mid -0.249642 0.249642)
							(end -0.2794 0.1778)
						)
						(arc
							(start -0.2794 -0.1778)
							(mid -0.249642 -0.249642)
							(end -0.1778 -0.2794)
						)
						(arc
							(start 0.1778 -0.2794)
							(mid 0.249642 -0.249642)
							(end 0.2794 -0.1778)
						)
						(arc
							(start 0.2794 0.1778)
							(mid 0.249642 0.249642)
							(end 0.1778 0.2794)
						)
					)
					(width 0)
					(fill yes)
				)
			)
		)
	)
	(footprint ""
		(layer "B.Cu")
		(at 17.4244 -133.8326 90)
		(property "Reference" "R255"
			(at 0 0 90)
			(layer "B.SilkS")
			(hide yes)
			(effects
				(font
					(size 1.27 1.27)
				)
				(justify mirror)
			)
		)
		(property "Value" "4K7R2F-GP"
			(at -0.064008 -3.993896 90)
			(unlocked yes)
			(layer "B.Fab")
			(hide yes)
			(effects
				(font
					(size 1.016 1.016)
					(thickness 0.1524)
				)
				(justify mirror)
			)
		)
		(property "Device Type" "R402H16"
			(at -0.064008 -5.517896 90)
			(unlocked yes)
			(layer "B.Fab")
			(hide yes)
			(effects
				(font
					(size 1.016 1.016)
					(thickness 0.1524)
				)
				(justify mirror)
			)
		)
		(duplicate_pad_numbers_are_jumpers no)
		(fp_line
			(start 0.508 -0.9398)
			(end 0.508 0.9398)
			(stroke
				(width 0.1524)
				(type default)
			)
			(layer "B.SilkS")
		)
		(fp_line
			(start -0.508 -0.9398)
			(end 0.508 -0.9398)
			(stroke
				(width 0.1524)
				(type default)
			)
			(layer "B.SilkS")
		)
		(fp_rect
			(start 0.508 0.9398)
			(end -0.508 -0.9398)
			(stroke
				(width 0)
				(type default)
			)
			(fill no)
			(layer "B.CrtYd")
		)
		(fp_rect
			(start 0.508 0.9398)
			(end -0.508 -0.9398)
			(stroke
				(width 0)
				(type default)
			)
			(fill no)
			(layer "B.Fab")
		)
		(pad "1" smd custom
			(at 0 -0.4445 270)
			(size 0.1397 0.1397)
			(layers "B.Cu" "B.Mask" "B.Paste")
			(net "EXP_TRAY_ID")
			(options
				(clearance outline)
				(anchor circle)
			)
			(primitives
				(gr_poly
					(pts
						(arc
							(start -0.1778 0.2794)
							(mid -0.249642 0.249642)
							(end -0.2794 0.1778)
						)
						(arc
							(start -0.2794 -0.1778)
							(mid -0.249642 -0.249642)
							(end -0.1778 -0.2794)
						)
						(arc
							(start 0.1778 -0.2794)
							(mid 0.249642 -0.249642)
							(end 0.2794 -0.1778)
						)
						(arc
							(start 0.2794 0.1778)
							(mid 0.249642 0.249642)
							(end 0.1778 0.2794)
						)
					)
					(width 0)
					(fill yes)
				)
			)
		)
		(pad "2" smd custom
			(at 0 0.4445 270)
			(size 0.1397 0.1397)
			(layers "B.Cu" "B.Mask" "B.Paste")
			(net "P3V3_STBY")
			(options
				(clearance outline)
				(anchor circle)
			)
			(primitives
				(gr_poly
					(pts
						(arc
							(start -0.1778 0.2794)
							(mid -0.249642 0.249642)
							(end -0.2794 0.1778)
						)
						(arc
							(start -0.2794 -0.1778)
							(mid -0.249642 -0.249642)
							(end -0.1778 -0.2794)
						)
						(arc
							(start 0.1778 -0.2794)
							(mid 0.249642 -0.249642)
							(end 0.2794 -0.1778)
						)
						(arc
							(start 0.2794 0.1778)
							(mid 0.249642 0.249642)
							(end 0.1778 0.2794)
						)
					)
					(width 0)
					(fill yes)
				)
			)
		)
	)
)
